(kicad_pcb
	(version 20260206)
	(generator "pcbnew")
	(generator_version "10.0")
	(general
		(thickness 1.6)
		(legacy_teardrops no)
	)
	(paper "A4")
	(title_block
		(title "Bryce Canyon_F.DPB_16315-1-OCP.brd")
		(comment 1 "Bryce Canyon / footprints 55-63 of 2223")
	)
	(layers
		(0 "F.Cu" signal "TOP")
		(4 "In1.Cu" signal "L2GND")
		(6 "In2.Cu" signal "L3")
		(8 "In3.Cu" signal "L4GND")
		(10 "In4.Cu" signal "L5")
		(12 "In5.Cu" signal "L6VCC")
		(14 "In6.Cu" signal "L7VCC")
		(16 "In7.Cu" signal "L8")
		(18 "In8.Cu" signal "L9GND")
		(20 "In9.Cu" signal "L10")
		(22 "In10.Cu" signal "L11GND")
		(2 "B.Cu" signal "BOTTOM")
		(9 "F.Adhes" user "F.Adhesive")
		(11 "B.Adhes" user "B.Adhesive")
		(13 "F.Paste" user "Package Geometry/Pastemask Top")
		(15 "B.Paste" user "Package Geometry/Pastemask Bottom")
		(5 "F.SilkS" user "Ref Des/Silkscreen Top")
		(7 "B.SilkS" user "Ref Des/Silkscreen Bottom")
		(1 "F.Mask" user "Board Geometry/Soldermask Top")
		(3 "B.Mask" user "Board Geometry/Soldermask Bottom")
		(17 "Dwgs.User" user "User.Drawings")
		(19 "Cmts.User" user "User.Comments")
		(21 "Eco1.User" user "User.Eco1")
		(23 "Eco2.User" user "User.Eco2")
		(25 "Edge.Cuts" user "Board Geometry/Outline")
		(27 "Margin" user)
		(31 "F.CrtYd" user "Package Geometry/Place Bound Top")
		(29 "B.CrtYd" user "Package Geometry/Place Bound Bottom")
		(35 "F.Fab" user "Ref Des/Assembly Top")
		(33 "B.Fab" user "Ref Des/Assembly Bottom")
	)
	(footprint ""
		(layer "F.Cu")
		(at 83.530948 -292.778942 -90)
		(property "Reference" "C66"
			(at 0 0 270)
			(layer "F.SilkS")
			(hide yes)
			(effects
				(font
					(size 1.27 1.27)
				)
			)
		)
		(property "Value" "SC1U16V3KX-5GP"
			(at 0 -2.8194 270)
			(unlocked yes)
			(layer "F.Fab")
			(hide yes)
			(effects
				(font
					(size 1.016 1.016)
					(thickness 0.1524)
				)
			)
		)
		(property "Device Type" "C603H36"
			(at 0 -4.3434 270)
			(unlocked yes)
			(layer "F.Fab")
			(hide yes)
			(effects
				(font
					(size 1.016 1.016)
					(thickness 0.1524)
				)
			)
		)
		(duplicate_pad_numbers_are_jumpers no)
		(fp_line
			(start 0.508 0)
			(end -0.508 0)
			(stroke
				(width 0.2032)
				(type default)
			)
			(layer "F.SilkS")
		)
		(fp_rect
			(start -0.5842 1.3335)
			(end 0.5842 -1.3335)
			(stroke
				(width 0)
				(type default)
			)
			(fill no)
			(layer "F.CrtYd")
		)
		(fp_rect
			(start -0.5842 1.3335)
			(end 0.5842 -1.3335)
			(stroke
				(width 0)
				(type default)
			)
			(fill no)
			(layer "F.Fab")
		)
		(pad "1" smd custom
			(at 0 -0.762 270)
			(size 0.2159 0.2159)
			(layers "F.Cu" "F.Mask" "F.Paste")
			(net "P5V_HDD2")
			(options
				(clearance outline)
				(anchor circle)
			)
			(primitives
				(gr_poly
					(pts
						(arc
							(start -0.3302 -0.4318)
							(mid -0.402042 -0.402042)
							(end -0.4318 -0.3302)
						)
						(arc
							(start -0.4318 0.3302)
							(mid -0.402042 0.402042)
							(end -0.3302 0.4318)
						)
						(arc
							(start 0.3302 0.4318)
							(mid 0.402042 0.402042)
							(end 0.4318 0.3302)
						)
						(arc
							(start 0.4318 -0.3302)
							(mid 0.402042 -0.402042)
							(end 0.3302 -0.4318)
						)
					)
					(width 0)
					(fill yes)
				)
			)
		)
		(pad "2" smd custom
			(at 0 0.762 270)
			(size 0.2159 0.2159)
			(layers "F.Cu" "F.Mask" "F.Paste")
			(net "GND")
			(options
				(clearance outline)
				(anchor circle)
			)
			(primitives
				(gr_poly
					(pts
						(arc
							(start -0.3302 -0.4318)
							(mid -0.402042 -0.402042)
							(end -0.4318 -0.3302)
						)
						(arc
							(start -0.4318 0.3302)
							(mid -0.402042 0.402042)
							(end -0.3302 0.4318)
						)
						(arc
							(start 0.3302 0.4318)
							(mid 0.402042 0.402042)
							(end 0.4318 0.3302)
						)
						(arc
							(start 0.4318 -0.3302)
							(mid 0.402042 -0.402042)
							(end 0.3302 -0.4318)
						)
					)
					(width 0)
					(fill yes)
				)
			)
		)
	)
	(footprint ""
		(layer "F.Cu")
		(at 55.282846 -62.270894)
		(property "Reference" "R704"
			(at 0 0 0)
			(layer "F.SilkS")
			(hide yes)
			(effects
				(font
					(size 1.27 1.27)
				)
			)
		)
		(property "Value" "2R6F-GP"
			(at -0.0508 -4.8514 0)
			(unlocked yes)
			(layer "F.Fab")
			(hide yes)
			(effects
				(font
					(size 1.016 1.016)
					(thickness 0.1524)
				)
			)
		)
		(property "Device Type" "R1206H26"
			(at 0 -6.3754 0)
			(unlocked yes)
			(layer "F.Fab")
			(hide yes)
			(effects
				(font
					(size 1.016 1.016)
					(thickness 0.1524)
				)
			)
		)
		(duplicate_pad_numbers_are_jumpers no)
		(fp_line
			(start -1.016 -2.2352)
			(end 1.016 -2.2352)
			(stroke
				(width 0.1524)
				(type default)
			)
			(layer "F.SilkS")
		)
		(fp_line
			(start -1.016 2.2352)
			(end -1.016 -2.2352)
			(stroke
				(width 0.1524)
				(type default)
			)
			(layer "F.SilkS")
		)
		(fp_line
			(start 1.016 -2.2352)
			(end 1.016 2.2352)
			(stroke
				(width 0.1524)
				(type default)
			)
			(layer "F.SilkS")
		)
		(fp_line
			(start 1.016 2.2352)
			(end -1.016 2.2352)
			(stroke
				(width 0.1524)
				(type default)
			)
			(layer "F.SilkS")
		)
		(fp_rect
			(start -1.0922 2.3114)
			(end 1.0922 -2.3114)
			(stroke
				(width 0)
				(type default)
			)
			(fill no)
			(layer "F.CrtYd")
		)
		(fp_poly
			(pts
				(xy -1.0922 -2.3114) (xy 1.0922 -2.3114) (xy 1.0922 2.3114) (xy -1.0922 2.3114)
			)
			(stroke
				(width 0)
				(type default)
			)
			(fill no)
			(layer "F.Fab")
		)
		(pad "1" smd rect
			(at 0 -1.397)
			(size 1.651 1.27)
			(layers "F.Cu" "F.Mask" "F.Paste")
			(net "P5V_HDD25")
		)
		(pad "2" smd rect
			(at 0 1.397)
			(size 1.651 1.27)
			(layers "F.Cu" "F.Mask" "F.Paste")
			(net "5V_PRE_25")
		)
	)
	(footprint ""
		(layer "F.Cu")
		(at 50.050446 -45.633894)
		(property "Reference" "R722"
			(at 0 0 0)
			(layer "F.SilkS")
			(hide yes)
			(effects
				(font
					(size 1.27 1.27)
				)
			)
		)
		(property "Value" "0R2J-2-GP"
			(at 0.064008 -3.993896 0)
			(unlocked yes)
			(layer "F.Fab")
			(hide yes)
			(effects
				(font
					(size 1.016 1.016)
					(thickness 0.1524)
				)
			)
		)
		(property "Device Type" "R402H16"
			(at 0.064008 -5.517896 0)
			(unlocked yes)
			(layer "F.Fab")
			(hide yes)
			(effects
				(font
					(size 1.016 1.016)
					(thickness 0.1524)
				)
			)
		)
		(duplicate_pad_numbers_are_jumpers no)
		(fp_line
			(start -0.508 -0.9398)
			(end -0.508 0.9398)
			(stroke
				(width 0.1524)
				(type default)
			)
			(layer "F.SilkS")
		)
		(fp_line
			(start 0.508 -0.9398)
			(end -0.508 -0.9398)
			(stroke
				(width 0.1524)
				(type default)
			)
			(layer "F.SilkS")
		)
		(fp_rect
			(start -0.508 0.9398)
			(end 0.508 -0.9398)
			(stroke
				(width 0)
				(type default)
			)
			(fill no)
			(layer "F.CrtYd")
		)
		(fp_rect
			(start -0.508 0.9398)
			(end 0.508 -0.9398)
			(stroke
				(width 0)
				(type default)
			)
			(fill no)
			(layer "F.Fab")
		)
		(pad "1" smd custom
			(at 0 -0.4445)
			(size 0.1397 0.1397)
			(layers "F.Cu" "F.Mask" "F.Paste")
			(net "SW_HDD_G25")
			(options
				(clearance outline)
				(anchor circle)
			)
			(primitives
				(gr_poly
					(pts
						(arc
							(start -0.1778 -0.2794)
							(mid -0.249642 -0.249642)
							(end -0.2794 -0.1778)
						)
						(arc
							(start -0.2794 0.1778)
							(mid -0.249642 0.249642)
							(end -0.1778 0.2794)
						)
						(arc
							(start 0.1778 0.2794)
							(mid 0.249642 0.249642)
							(end 0.2794 0.1778)
						)
						(arc
							(start 0.2794 -0.1778)
							(mid 0.249642 -0.249642)
							(end 0.1778 -0.2794)
						)
					)
					(width 0)
					(fill yes)
				)
			)
		)
		(pad "2" smd custom
			(at 0 0.4445)
			(size 0.1397 0.1397)
			(layers "F.Cu" "F.Mask" "F.Paste")
			(net "SW_HDD_R25")
			(options
				(clearance outline)
				(anchor circle)
			)
			(primitives
				(gr_poly
					(pts
						(arc
							(start -0.1778 -0.2794)
							(mid -0.249642 -0.249642)
							(end -0.2794 -0.1778)
						)
						(arc
							(start -0.2794 0.1778)
							(mid -0.249642 0.249642)
							(end -0.1778 0.2794)
						)
						(arc
							(start 0.1778 0.2794)
							(mid 0.249642 0.249642)
							(end 0.2794 0.1778)
						)
						(arc
							(start 0.2794 -0.1778)
							(mid 0.249642 -0.249642)
							(end 0.1778 -0.2794)
						)
					)
					(width 0)
					(fill yes)
				)
			)
		)
	)
	(footprint ""
		(layer "F.Cu")
		(at 20.049998 -291.000942 -90)
		(property "Reference" "C509"
			(at 0 0 270)
			(layer "F.SilkS")
			(hide yes)
			(effects
				(font
					(size 1.27 1.27)
				)
			)
		)
		(property "Value" "SC10U16V6KX-2GP"
			(at -0.0762 -5.1308 270)
			(unlocked yes)
			(layer "F.Fab")
			(hide yes)
			(effects
				(font
					(size 1.016 1.016)
					(thickness 0.1524)
				)
			)
		)
		(property "Device Type" "C1206H71"
			(at -0.127 -6.6548 270)
			(unlocked yes)
			(layer "F.Fab")
			(hide yes)
			(effects
				(font
					(size 1.016 1.016)
					(thickness 0.1524)
				)
			)
		)
		(duplicate_pad_numbers_are_jumpers no)
		(fp_line
			(start -1.016 2.2352)
			(end -1.016 0.8382)
			(stroke
				(width 0.1524)
				(type default)
			)
			(layer "F.SilkS")
		)
		(fp_line
			(start 1.016 2.2352)
			(end -1.016 2.2352)
			(stroke
				(width 0.1524)
				(type default)
			)
			(layer "F.SilkS")
		)
		(fp_line
			(start 1.016 0.8382)
			(end 1.016 2.2352)
			(stroke
				(width 0.1524)
				(type default)
			)
			(layer "F.SilkS")
		)
		(fp_line
			(start -1.016 -0.8382)
			(end -1.016 -2.2352)
			(stroke
				(width 0.1524)
				(type default)
			)
			(layer "F.SilkS")
		)
		(fp_line
			(start -1.016 -2.2352)
			(end 1.016 -2.2352)
			(stroke
				(width 0.1524)
				(type default)
			)
			(layer "F.SilkS")
		)
		(fp_line
			(start 1.016 -2.2352)
			(end 1.016 -0.8382)
			(stroke
				(width 0.1524)
				(type default)
			)
			(layer "F.SilkS")
		)
		(fp_rect
			(start -1.0922 2.3114)
			(end 1.0922 -2.3114)
			(stroke
				(width 0)
				(type default)
			)
			(fill no)
			(layer "F.CrtYd")
		)
		(fp_poly
			(pts
				(xy 1.0922 -2.3114) (xy 1.0922 2.3114) (xy -1.0922 2.3114) (xy -1.0922 -2.3114)
			)
			(stroke
				(width 0)
				(type default)
			)
			(fill no)
			(layer "F.Fab")
		)
		(pad "1" smd rect
			(at 0 -1.397 270)
			(size 1.651 1.27)
			(layers "F.Cu" "F.Mask" "F.Paste")
			(net "P5V_HDD0")
		)
		(pad "2" smd rect
			(at 0 1.397 270)
			(size 1.651 1.27)
			(layers "F.Cu" "F.Mask" "F.Paste")
			(net "GND")
		)
	)
	(footprint ""
		(layer "F.Cu")
		(at 267.197078 -128.448308 90)
		(property "Reference" "TP184"
			(at 0 0 90)
			(layer "F.SilkS")
			(hide yes)
			(effects
				(font
					(size 1.27 1.27)
				)
			)
		)
		(property "Value" "TPAD32-GP"
			(at -0.0508 -1.6764 90)
			(unlocked yes)
			(layer "F.Fab")
			(hide yes)
			(effects
				(font
					(size 1.016 1.016)
					(thickness 0.1524)
				)
			)
		)
		(property "Device Type" "TPAD32"
			(at -0.0508 -3.2004 90)
			(unlocked yes)
			(layer "F.Fab")
			(hide yes)
			(effects
				(font
					(size 1.016 1.016)
					(thickness 0.1524)
				)
			)
		)
		(duplicate_pad_numbers_are_jumpers no)
		(fp_poly
			(pts
				(arc
					(start 0 0.4064)
					(mid 0 -0.4064)
					(end 0 0.4064)
				)
			)
			(stroke
				(width 0)
				(type default)
			)
			(fill no)
			(layer "F.CrtYd")
		)
		(fp_poly
			(pts
				(arc
					(start 0 0.7112)
					(mid 0 -0.7112)
					(end 0 0.7112)
				)
			)
			(stroke
				(width 0)
				(type default)
			)
			(fill no)
			(layer "F.Fab")
		)
		(pad "1" smd circle
			(at 0 0 90)
			(size 0.8128 0.8128)
			(layers "F.Cu" "F.Mask" "F.Paste")
			(net "TP_COMP_B_SATA_P0_TX_DN")
		)
	)
	(footprint ""
		(layer "F.Cu")
		(at 395.20495 -45.252894 -90)
		(property "Reference" "Q193"
			(at 0 0 270)
			(layer "F.SilkS")
			(hide yes)
			(effects
				(font
					(size 1.27 1.27)
				)
			)
		)
		(property "Value" "2N7002KDW-GP"
			(at -2.3622 -8.2042 270)
			(unlocked yes)
			(layer "F.Fab")
			(hide yes)
			(effects
				(font
					(size 1.016 1.016)
					(thickness 0.1524)
				)
			)
		)
		(property "Device Type" "SOT-363H44"
			(at -2.3622 -10.1092 270)
			(unlocked yes)
			(layer "F.Fab")
			(hide yes)
			(effects
				(font
					(size 1.016 1.016)
					(thickness 0.1524)
				)
			)
		)
		(duplicate_pad_numbers_are_jumpers no)
		(fp_line
			(start -1.4478 1.7018)
			(end 1.4478 1.7018)
			(stroke
				(width 0.1524)
				(type default)
			)
			(layer "F.SilkS")
		)
		(fp_line
			(start 1.4478 1.7018)
			(end 1.4478 -1.7018)
			(stroke
				(width 0.1524)
				(type default)
			)
			(layer "F.SilkS")
		)
		(fp_line
			(start -1.27 1.524)
			(end -1.27 0.6604)
			(stroke
				(width 0.4826)
				(type default)
			)
			(layer "F.SilkS")
		)
		(fp_line
			(start -1.4478 -1.7018)
			(end -1.4478 1.7018)
			(stroke
				(width 0.1524)
				(type default)
			)
			(layer "F.SilkS")
		)
		(fp_line
			(start 1.4478 -1.7018)
			(end -1.4478 -1.7018)
			(stroke
				(width 0.1524)
				(type default)
			)
			(layer "F.SilkS")
		)
		(fp_poly
			(pts
				(xy -1.524 -1.778) (xy 1.524 -1.778) (xy 1.524 1.778) (xy -1.524 1.778)
			)
			(stroke
				(width 0)
				(type default)
			)
			(fill no)
			(layer "F.CrtYd")
		)
		(fp_poly
			(pts
				(xy -1.524 -1.778) (xy 1.524 -1.778) (xy 1.524 1.778) (xy -1.524 1.778)
			)
			(stroke
				(width 0)
				(type default)
			)
			(fill no)
			(layer "F.Fab")
		)
		(pad "1" smd rect
			(at -0.65024 0.9398 270)
			(size 0.4064 1.016)
			(layers "F.Cu" "F.Mask" "F.Paste")
			(net "GND")
		)
		(pad "2" smd rect
			(at 0 0.9398 270)
			(size 0.4064 1.016)
			(layers "F.Cu" "F.Mask" "F.Paste")
			(net "SW_PWR_R_HDD32")
		)
		(pad "3" smd rect
			(at 0.65024 0.9398 270)
			(size 0.4064 1.016)
			(layers "F.Cu" "F.Mask" "F.Paste")
			(net "SW_HDD_P32")
		)
		(pad "4" smd rect
			(at 0.65024 -0.9398 270)
			(size 0.4064 1.016)
			(layers "F.Cu" "F.Mask" "F.Paste")
			(net "GND")
		)
		(pad "5" smd rect
			(at 0 -0.9398 270)
			(size 0.4064 1.016)
			(layers "F.Cu" "F.Mask" "F.Paste")
			(net "SW_HDD_G32")
		)
		(pad "6" smd rect
			(at -0.65024 -0.9398 270)
			(size 0.4064 1.016)
			(layers "F.Cu" "F.Mask" "F.Paste")
			(net "SW_HDD_R32")
		)
	)
	(footprint ""
		(layer "F.Cu")
		(at 424.469052 -189.335918 180)
		(property "Reference" "C320"
			(at 0 0 180)
			(layer "F.SilkS")
			(hide yes)
			(effects
				(font
					(size 1.27 1.27)
				)
			)
		)
		(property "Value" "SC1U25V3KX-GP"
			(at 0 -2.8194 180)
			(unlocked yes)
			(layer "F.Fab")
			(hide yes)
			(effects
				(font
					(size 1.016 1.016)
					(thickness 0.1524)
				)
			)
		)
		(property "Device Type" "C603H36"
			(at 0 -4.3434 180)
			(unlocked yes)
			(layer "F.Fab")
			(hide yes)
			(effects
				(font
					(size 1.016 1.016)
					(thickness 0.1524)
				)
			)
		)
		(duplicate_pad_numbers_are_jumpers no)
		(fp_line
			(start 0.508 0)
			(end -0.508 0)
			(stroke
				(width 0.2032)
				(type default)
			)
			(layer "F.SilkS")
		)
		(fp_rect
			(start -0.5842 1.3335)
			(end 0.5842 -1.3335)
			(stroke
				(width 0)
				(type default)
			)
			(fill no)
			(layer "F.CrtYd")
		)
		(fp_rect
			(start -0.5842 1.3335)
			(end 0.5842 -1.3335)
			(stroke
				(width 0)
				(type default)
			)
			(fill no)
			(layer "F.Fab")
		)
		(pad "1" smd custom
			(at 0 -0.762 180)
			(size 0.2159 0.2159)
			(layers "F.Cu" "F.Mask" "F.Paste")
			(net "P12V_HDD21")
			(options
				(clearance outline)
				(anchor circle)
			)
			(primitives
				(gr_poly
					(pts
						(arc
							(start -0.3302 -0.4318)
							(mid -0.402042 -0.402042)
							(end -0.4318 -0.3302)
						)
						(arc
							(start -0.4318 0.3302)
							(mid -0.402042 0.402042)
							(end -0.3302 0.4318)
						)
						(arc
							(start 0.3302 0.4318)
							(mid 0.402042 0.402042)
							(end 0.4318 0.3302)
						)
						(arc
							(start 0.4318 -0.3302)
							(mid 0.402042 -0.402042)
							(end 0.3302 -0.4318)
						)
					)
					(width 0)
					(fill yes)
				)
			)
		)
		(pad "2" smd custom
			(at 0 0.762 180)
			(size 0.2159 0.2159)
			(layers "F.Cu" "F.Mask" "F.Paste")
			(net "GND")
			(options
				(clearance outline)
				(anchor circle)
			)
			(primitives
				(gr_poly
					(pts
						(arc
							(start -0.3302 -0.4318)
							(mid -0.402042 -0.402042)
							(end -0.4318 -0.3302)
						)
						(arc
							(start -0.4318 0.3302)
							(mid -0.402042 0.402042)
							(end -0.3302 0.4318)
						)
						(arc
							(start 0.3302 0.4318)
							(mid 0.402042 0.402042)
							(end 0.4318 0.3302)
						)
						(arc
							(start 0.4318 -0.3302)
							(mid 0.402042 -0.402042)
							(end 0.3302 -0.4318)
						)
					)
					(width 0)
					(fill yes)
				)
			)
		)
	)
	(footprint ""
		(layer "F.Cu")
		(at 220.861636 -346.331794 180)
		(property "Reference" "TP2"
			(at 0 0 180)
			(layer "F.SilkS")
			(hide yes)
			(effects
				(font
					(size 1.27 1.27)
				)
			)
		)
		(property "Value" "TPAD32-GP"
			(at -0.0508 -1.6764 180)
			(unlocked yes)
			(layer "F.Fab")
			(hide yes)
			(effects
				(font
					(size 1.016 1.016)
					(thickness 0.1524)
				)
			)
		)
		(property "Device Type" "TPAD32"
			(at -0.0508 -3.2004 180)
			(unlocked yes)
			(layer "F.Fab")
			(hide yes)
			(effects
				(font
					(size 1.016 1.016)
					(thickness 0.1524)
				)
			)
		)
		(duplicate_pad_numbers_are_jumpers no)
		(fp_poly
			(pts
				(arc
					(start -0.4064 0)
					(mid 0.4064 0)
					(end -0.4064 0)
				)
			)
			(stroke
				(width 0)
				(type default)
			)
			(fill no)
			(layer "F.CrtYd")
		)
		(fp_poly
			(pts
				(arc
					(start -0.7112 0)
					(mid 0.7112 0)
					(end -0.7112 0)
				)
			)
			(stroke
				(width 0)
				(type default)
			)
			(fill no)
			(layer "F.Fab")
		)
		(pad "1" smd circle
			(at 0 0 180)
			(size 0.8128 0.8128)
			(layers "F.Cu" "F.Mask" "F.Paste")
			(net "VOL_SEN_INT_N")
		)
	)
	(footprint ""
		(layer "F.Cu")
		(at 413.318452 -62.143894 90)
		(property "Reference" "R889"
			(at 0 0 90)
			(layer "F.SilkS")
			(hide yes)
			(effects
				(font
					(size 1.27 1.27)
				)
			)
		)
		(property "Value" "10KR2F-2-GP"
			(at 0.064008 -3.993896 90)
			(unlocked yes)
			(layer "F.Fab")
			(hide yes)
			(effects
				(font
					(size 1.016 1.016)
					(thickness 0.1524)
				)
			)
		)
		(property "Device Type" "R402H16"
			(at 0.064008 -5.517896 90)
			(unlocked yes)
			(layer "F.Fab")
			(hide yes)
			(effects
				(font
					(size 1.016 1.016)
					(thickness 0.1524)
				)
			)
		)
		(duplicate_pad_numbers_are_jumpers no)
		(fp_line
			(start 0.508 -0.9398)
			(end -0.508 -0.9398)
			(stroke
				(width 0.1524)
				(type default)
			)
			(layer "F.SilkS")
		)
		(fp_line
			(start -0.508 -0.9398)
			(end -0.508 0.9398)
			(stroke
				(width 0.1524)
				(type default)
			)
			(layer "F.SilkS")
		)
		(fp_rect
			(start -0.508 0.9398)
			(end 0.508 -0.9398)
			(stroke
				(width 0)
				(type default)
			)
			(fill no)
			(layer "F.CrtYd")
		)
		(fp_rect
			(start -0.508 0.9398)
			(end 0.508 -0.9398)
			(stroke
				(width 0)
				(type default)
			)
			(fill no)
			(layer "F.Fab")
		)
		(pad "1" smd custom
			(at 0 -0.4445 90)
			(size 0.1397 0.1397)
			(layers "F.Cu" "F.Mask" "F.Paste")
			(net "P3V3_STBY_A")
			(options
				(clearance outline)
				(anchor circle)
			)
			(primitives
				(gr_poly
					(pts
						(arc
							(start -0.1778 -0.2794)
							(mid -0.249642 -0.249642)
							(end -0.2794 -0.1778)
						)
						(arc
							(start -0.2794 0.1778)
							(mid -0.249642 0.249642)
							(end -0.1778 0.2794)
						)
						(arc
							(start 0.1778 0.2794)
							(mid 0.249642 0.249642)
							(end 0.2794 0.1778)
						)
						(arc
							(start 0.2794 -0.1778)
							(mid 0.249642 -0.249642)
							(end 0.1778 -0.2794)
						)
					)
					(width 0)
					(fill yes)
				)
			)
		)
		(pad "2" smd custom
			(at 0 0.4445 90)
			(size 0.1397 0.1397)
			(layers "F.Cu" "F.Mask" "F.Paste")
			(net "HDD_PRSNT_33")
			(options
				(clearance outline)
				(anchor circle)
			)
			(primitives
				(gr_poly
					(pts
						(arc
							(start -0.1778 -0.2794)
							(mid -0.249642 -0.249642)
							(end -0.2794 -0.1778)
						)
						(arc
							(start -0.2794 0.1778)
							(mid -0.249642 0.249642)
							(end -0.1778 0.2794)
						)
						(arc
							(start 0.1778 0.2794)
							(mid 0.249642 0.249642)
							(end 0.2794 0.1778)
						)
						(arc
							(start 0.2794 -0.1778)
							(mid 0.249642 -0.249642)
							(end 0.1778 -0.2794)
						)
					)
					(width 0)
					(fill yes)
				)
			)
		)
	)
)
